# SCM (Grand Teton) — schematic netlist excerpt (pin names and nets, part order shuffled) for the footprints in the layout excerpt that follows; sources: Cadence DE-HDL packaged netlist, KiCad conversion of 12092022_DA0F0TMDCD0_F0T_Management_Board_D_brd_V3_OCP.brd

R384  Q_RES  100 1% CHIP  pkg 0402LF  page 28 : A = USB_OC0_REAR_N ; B = USB_OC0_REAR_R_N
PR193  Q_RES  0 5% CHIP  pkg 0402LF  page 56 : A = P3V3_AUX ; B = PVCC2_AUX

(kicad_pcb
	(version 20260206)
	(generator "pcbnew")
	(generator_version "10.0")
	(general
		(thickness 1.6)
		(legacy_teardrops no)
	)
	(paper "A4")
	(title_block
		(title "12092022_DA0F0TMDCD0_F0T_Management_Board_D_brd_V3_OCP.brd")
		(comment 1 "Grand Teton / footprints 213-214 of 1440")
	)
	(layers
		(0 "F.Cu" signal "TOP")
		(4 "In1.Cu" signal "GND")
		(6 "In2.Cu" signal "IN1")
		(8 "In3.Cu" signal "GND1")
		(10 "In4.Cu" signal "IN2")
		(12 "In5.Cu" signal "VCC")
		(14 "In6.Cu" signal "VCC1")
		(16 "In7.Cu" signal "IN3")
		(18 "In8.Cu" signal "GND2")
		(20 "In9.Cu" signal "IN4")
		(22 "In10.Cu" signal "GND3")
		(2 "B.Cu" signal "BOTTOM")
		(9 "F.Adhes" user "F.Adhesive")
		(11 "B.Adhes" user "B.Adhesive")
		(13 "F.Paste" user "Package Geometry/Pastemask Top")
		(15 "B.Paste" user "Package Geometry/Pastemask Bottom")
		(5 "F.SilkS" user "Ref Des/Silkscreen Top")
		(7 "B.SilkS" user "Ref Des/Silkscreen Bottom")
		(1 "F.Mask" user "Board Geometry/Soldermask Top")
		(3 "B.Mask" user "Board Geometry/Soldermask Bottom")
		(17 "Dwgs.User" user "User.Drawings")
		(19 "Cmts.User" user "User.Comments")
		(21 "Eco1.User" user "User.Eco1")
		(23 "Eco2.User" user "User.Eco2")
		(25 "Edge.Cuts" user "Board Geometry/Outline")
		(27 "Margin" user)
		(31 "F.CrtYd" user "Package Geometry/Place Bound Top")
		(29 "B.CrtYd" user "Package Geometry/Place Bound Bottom")
		(35 "F.Fab" user "Ref Des/Assembly Top")
		(33 "B.Fab" user "Ref Des/Assembly Bottom")
	)
	(footprint ""
		(layer "F.Cu")
		(at 46.863 -23.368 180)
		(property "Reference" "R384"
			(at 0 0 180)
			(layer "F.SilkS")
			(hide yes)
			(effects
				(font
					(size 1.27 1.27)
				)
			)
		)
		(property "Value" ""
			(at 0 0 180)
			(layer "F.Fab")
			(effects
				(font
					(size 1.27 1.27)
				)
			)
		)
		(duplicate_pad_numbers_are_jumpers no)
		(fp_line
			(start 0.7874 0.4064)
			(end -0.7874 0.4064)
			(stroke
				(width 0.1524)
				(type default)
			)
			(layer "F.SilkS")
		)
		(fp_line
			(start 0.7874 -0.4064)
			(end 0.7874 0.4064)
			(stroke
				(width 0.1524)
				(type default)
			)
			(layer "F.SilkS")
		)
		(fp_line
			(start -0.7874 0.4064)
			(end -0.7874 -0.4064)
			(stroke
				(width 0.1524)
				(type default)
			)
			(layer "F.SilkS")
		)
		(fp_line
			(start -0.7874 -0.4064)
			(end 0.7874 -0.4064)
			(stroke
				(width 0.1524)
				(type default)
			)
			(layer "F.SilkS")
		)
		(fp_line
			(start 0.67945 0.3048)
			(end 0.120396 0.3048)
			(stroke
				(width 0.1)
				(type default)
			)
			(layer "F.Fab")
		)
		(fp_line
			(start 0.67945 -0.3048)
			(end 0.67945 0.3048)
			(stroke
				(width 0.1)
				(type default)
			)
			(layer "F.Fab")
		)
		(fp_line
			(start 0.12065 -0.2794)
			(end 0.12065 -0.3048)
			(stroke
				(width 0.1)
				(type default)
			)
			(layer "F.Fab")
		)
		(fp_line
			(start 0.12065 -0.3048)
			(end 0.67945 -0.3048)
			(stroke
				(width 0.1)
				(type default)
			)
			(layer "F.Fab")
		)
		(fp_line
			(start 0.120396 0.3048)
			(end 0.120396 0.2794)
			(stroke
				(width 0.1)
				(type default)
			)
			(layer "F.Fab")
		)
		(fp_line
			(start 0.120396 0.2794)
			(end -0.12065 0.2794)
			(stroke
				(width 0.1)
				(type default)
			)
			(layer "F.Fab")
		)
		(fp_line
			(start -0.12065 0.3048)
			(end -0.67945 0.3048)
			(stroke
				(width 0.1)
				(type default)
			)
			(layer "F.Fab")
		)
		(fp_line
			(start -0.12065 0.2794)
			(end -0.12065 0.3048)
			(stroke
				(width 0.1)
				(type default)
			)
			(layer "F.Fab")
		)
		(fp_line
			(start -0.12065 -0.2794)
			(end 0.12065 -0.2794)
			(stroke
				(width 0.1)
				(type default)
			)
			(layer "F.Fab")
		)
		(fp_line
			(start -0.12065 -0.305054)
			(end -0.12065 -0.2794)
			(stroke
				(width 0.1)
				(type default)
			)
			(layer "F.Fab")
		)
		(fp_line
			(start -0.67945 0.3048)
			(end -0.67945 -0.305054)
			(stroke
				(width 0.1)
				(type default)
			)
			(layer "F.Fab")
		)
		(fp_line
			(start -0.67945 -0.305054)
			(end -0.12065 -0.305054)
			(stroke
				(width 0.1)
				(type default)
			)
			(layer "F.Fab")
		)
		(pad "1" smd circle
			(at -0.40005 0 180)
			(size 0 0)
			(layers "F.Cu" "F.Mask" "F.Paste")
			(net "USB_OC0_REAR_N")
		)
		(pad "2" smd circle
			(at 0.40005 0 180)
			(size 0 0)
			(layers "F.Cu" "F.Mask" "F.Paste")
			(net "USB_OC0_REAR_R_N")
		)
	)
	(footprint ""
		(layer "F.Cu")
		(at 24.3332 -30.6324 90)
		(property "Reference" "PR193"
			(at 0 0 90)
			(layer "F.SilkS")
			(hide yes)
			(effects
				(font
					(size 1.27 1.27)
				)
			)
		)
		(property "Value" ""
			(at 0 0 90)
			(layer "F.Fab")
			(effects
				(font
					(size 1.27 1.27)
				)
			)
		)
		(duplicate_pad_numbers_are_jumpers no)
		(fp_line
			(start 0.7874 -0.4064)
			(end 0.7874 0.4064)
			(stroke
				(width 0.1524)
				(type default)
			)
			(layer "F.SilkS")
		)
		(fp_line
			(start -0.7874 -0.4064)
			(end 0.7874 -0.4064)
			(stroke
				(width 0.1524)
				(type default)
			)
			(layer "F.SilkS")
		)
		(fp_line
			(start 0.7874 0.4064)
			(end -0.7874 0.4064)
			(stroke
				(width 0.1524)
				(type default)
			)
			(layer "F.SilkS")
		)
		(fp_line
			(start -0.7874 0.4064)
			(end -0.7874 -0.4064)
			(stroke
				(width 0.1524)
				(type default)
			)
			(layer "F.SilkS")
		)
		(fp_line
			(start -0.12065 -0.305054)
			(end -0.12065 -0.2794)
			(stroke
				(width 0.1)
				(type default)
			)
			(layer "F.Fab")
		)
		(fp_line
			(start -0.67945 -0.305054)
			(end -0.12065 -0.305054)
			(stroke
				(width 0.1)
				(type default)
			)
			(layer "F.Fab")
		)
		(fp_line
			(start 0.67945 -0.3048)
			(end 0.67945 0.3048)
			(stroke
				(width 0.1)
				(type default)
			)
			(layer "F.Fab")
		)
		(fp_line
			(start 0.12065 -0.3048)
			(end 0.67945 -0.3048)
			(stroke
				(width 0.1)
				(type default)
			)
			(layer "F.Fab")
		)
		(fp_line
			(start 0.12065 -0.2794)
			(end 0.12065 -0.3048)
			(stroke
				(width 0.1)
				(type default)
			)
			(layer "F.Fab")
		)
		(fp_line
			(start -0.12065 -0.2794)
			(end 0.12065 -0.2794)
			(stroke
				(width 0.1)
				(type default)
			)
			(layer "F.Fab")
		)
		(fp_line
			(start 0.120396 0.2794)
			(end -0.12065 0.2794)
			(stroke
				(width 0.1)
				(type default)
			)
			(layer "F.Fab")
		)
		(fp_line
			(start -0.12065 0.2794)
			(end -0.12065 0.3048)
			(stroke
				(width 0.1)
				(type default)
			)
			(layer "F.Fab")
		)
		(fp_line
			(start 0.67945 0.3048)
			(end 0.120396 0.3048)
			(stroke
				(width 0.1)
				(type default)
			)
			(layer "F.Fab")
		)
		(fp_line
			(start 0.120396 0.3048)
			(end 0.120396 0.2794)
			(stroke
				(width 0.1)
				(type default)
			)
			(layer "F.Fab")
		)
		(fp_line
			(start -0.12065 0.3048)
			(end -0.67945 0.3048)
			(stroke
				(width 0.1)
				(type default)
			)
			(layer "F.Fab")
		)
		(fp_line
			(start -0.67945 0.3048)
			(end -0.67945 -0.305054)
			(stroke
				(width 0.1)
				(type default)
			)
			(layer "F.Fab")
		)
		(pad "1" smd circle
			(at -0.40005 0 90)
			(size 0 0)
			(layers "F.Cu" "F.Mask" "F.Paste")
			(net "P3V3_AUX")
		)
		(pad "2" smd circle
			(at 0.40005 0 90)
			(size 0 0)
			(layers "F.Cu" "F.Mask" "F.Paste")
			(net "PVCC2_AUX")
		)
	)
)
